# HONEY BADGER PANTHER+ BOARD GCE-1B BOM of 55.B0701.D20G_20150213.xlsx — HONEY BADGER PANTHER+ BOARD GCE (bom)
| Level | Parent Number | Part Number | Description | Green Factor | Life Cycle State | Manufacturer | Manufacturer Part Number | Source | BOM Usage | M/P Code | S/D | Qty | UoM | Location |
| 1 | 55.B0701.D20G | 086.0002Y.0824 | SCRW WAFRE M2.0 TAP L3.8 | R2_C; | Released | TBD |  | Single |  | Purchase | DIP | 2 | PCS |  |
| 1 | 55.B0701.D20G | 086.0004K.0328 | SCRW WAFRE M2L8 NI | R2_C; | Released | TBD |  | Single |  | Purchase | DIP | 2 | PCS |  |
| 1 | 55.B0701.D20G | 087.14203.0214 | NUT M2X1.4 PC | R2_C; | Released | TBD |  | Single |  | Purchase | DIP | 2 | PCS |  |
| 1 | 55.B0701.D20G | 34.B0704.001 | HSINK_60X48X13.5_CLIP_PAD_HB | R2_SA; | Released | CCI | Void | Single |  | Purchase | DIP | 1 | PCS | U13 |
| 1 | 55.B0701.D20G | 42.B0721.001 | HDLR M SATA HB GREEN | R2_C; | Released | TBD |  | Single |  | Purchase | DIP | 1 | PCS |  |
| 1 | 55.B0701.D20G | 42.B0722.001 | HDLR NGFF HB GREEN | R2_C; | Released | TBD |  | Single |  | Purchase | DIP | 1 | PCS |  |
| 1 | 55.B0701.D20G | 42.B0723.001 | HDLR GRIP PANTHER HB PVT | R2_C; | Released | TBD |  | Single |  | Purchase | DIP | 1 | PCS |  |
| 1 | 55.B0701.D20G | 55.B0701.S20G | HONEY BADGER PANTHER+ BOARD GCE-1B | N/A; | Released |  |  |  | E | Manufacture | DIP | 1 | PCS |  |
| 2 | 55.B0701.S20G | 025.60003.0011 | ANCHOR 1R2P 21U-91-03TB22 ,NY9T | R2_SA; | Released | PINREX | 21U-91-03TB22 | Single |  | Purchase | SMT | 2 | PCS | CN1 CN2 |
| 2 | 55.B0701.S20G | 062.10011.0791 | SKT DDR3 SO DIMM 204P ASAA627-JERB0-7H | R2_SA; | Released | FOXCONN | ASAA627-JERB0-7H | Single |  | Purchase | SMT | 2 | PCS | DIMM1 DIMM3 |
| 2 | 55.B0701.S20G | 062.10011.0801 | SKT DDR3 SO DIMM 204P ASAA627-JESB0-7H | R2_SA; | Released | FOXCONN | ASAA627-JESB0-7H | Single |  | Purchase | SMT | 2 | PCS | DIMM2 DIMM4 |
| 2 | 55.B0701.S20G | 071.46228.000G | IC FPGA EP4CE6E22C8N EQFP 144P | R2_SA; | Released | ALTERA | EP4CE6E22C8N | Single |  | Purchase | SMT | 1 | PCS | U14 |
| 2 | 55.B0701.S20G | 071.94420.0003 | IC CLK 9VRS4420DKLFT VFQFPN 48P | R2_SA; | Released | IDT | 9VRS4420DKLFT | Single |  | Purchase | SMT | 1 | PCS | U16 |
| 2 | 55.B0701.S20G | 071.AVOTO.0C0U | IC CPU AVOTON C2750 2.4 GHZ 8C BGA B-0 | R2_SA; | Released | INTEL | 930444 FH8065401488906 SR1CS | Single |  | Purchase | SMT | 1 | PCS | U13 |
| 2 | 55.B0701.S20G | 078.47422.05F1 | CHIP CAP C 0.47U 25V K0402 X5R | R2_SA;HF_SA;G_SA; | Released | TAIYO;DARFON;MURATA;TDK;YAGEO | TMK105ABJ474KV-F;C1005X5R474KFT;GRM155R61E474KA12D;C1005X5R1E474KT;CC0402KRX5R8BB474 | Multiple |  | Purchase | SMT | 3 | PCS | C113 C17 C19 |
| 2 | 55.B0701.S20G | 078.47522.0211 | CHIP CAP C 4.7U 25V K0805 X7R | R2_SA;HF_SA;G_SA; | Released | WALSIN;SAMSUNG;MURATA | 0805B475K250CT;CL21B475KAFNNNE;GRM21BR71E475KA73L | Multiple |  | Purchase | SMT | 3 | PCS | PC159 PC188 PC90 |
| 2 | 55.B0701.S20G | 078.56222.02FS | CHIP CAP C 5600P 25V K0402 X7R | R2_SA;HF_SA;G_SA; | Released | TDK;MURATA;TAIYO | C1005X7R1E562KT000F;GRM155R71E562KA01D;TMK105B7562KV-F | Multiple |  | Purchase | SMT | 1 | PCS | PC5 |
| 2 | 55.B0701.S20G | 082.20014.0001 | OSC 5MHZ 25PPM 15PF 3.3V HXO-SC SMD | R2_SA; | Released | HOSONIC | DSCA5.00000NNS | Single |  | Purchase | SMT | 1 | PCS | OSC1 |
| 2 | 55.B0701.S20G | 20.F0441.060 | CONN SMD 60P BSH-030-01-L-D-A-TR ,LCP | R2_SA;HF_SA; | Released | SAMTEC | BSH-030-01-L-D-A-TR | Single |  | Purchase | SMT | 1 | PCS | CN4 |
| 2 | 55.B0701.S20G | 21.61881.205 | HEAD ML 2R10P HC3105F ,PA6T | R2_SA; | Released | FOXCONN | HC3105F | Single |  | Purchase | SMT | 1 | PCS | CN3 |
| 2 | 55.B0701.S20G | 48.B0729.01B | PCB 13130-1B HONEY BADGER PNTHR MB 12L G | R2_C; | Released | GCE |  | Single |  | Purchase | SMT | 1 | PCS |  |
| 2 | 55.B0701.S20G | 62.10043.B01 | SKT MINI PCI 52P 80003-3021 H=5.7MM SMD | R2_SA; | Released | BELLWETHER | 80003-3021 | Single |  | Purchase | SMT | 1 | PCS | CN5 |
| 2 | 55.B0701.S20G | 62.10043.S61 | SKT MINI PCIE/SATA KEY:M 67P 80159-4224 | R2_SA;HF_SA; | Released | BELLWETHER | 80159-4224 | Single |  | Purchase | SMT | 1 | PCS | NGFF1 |
| 2 | 55.B0701.S20G | 62.10089.091 | SKT SPI CONN 8P G6179T010-001 SMD | R2_SA; | Released | WIESON | G6179T010-001 | Single |  | Purchase | SMT | 1 | PCS | SKT1 |
| 2 | 55.B0701.S20G | 63.00000.00L | CHIP RES 0 J 1/10W 0603 | R2_SA;HF_SA;G_SA; | Released | TA-I ; RALEC ; YAGEO ; WALSIN | RM06JTN0 ; RTT03000JTP ; RC0603JR-070RL ; WR06X000PTL | Multiple |  | Purchase | SMT | 11 | PCS | PR109 PR114 PR13 PR170 PR25 PR54 PR58 PR80 PR97 R271 R273 |
| 2 | 55.B0701.S20G | 63.10233.15L | CHIP RES 1K J 1/10W 0603 | R2_SA;HF_SA;G_SA; | Released | TA-I ; RALEC ; YAGEO | RM06JTN102 ; RTT03102JTP ; RC0603JR-071KL | Multiple |  | Purchase | SMT | 1 | PCS | R272 |
| 2 | 55.B0701.S20G | 63.15134.1DL | CHIP RES 150 J 1/16W 0402 | R2_SA;HF_SA;G_SA; | Released | TA-I ; RALEC ; CYNTEC ; YAGEO | RM04JTN151 ; RTT02151JTH ; RR0510S-151-JN ; RC0402JR-07150RL | Multiple |  | Purchase | SMT | 2 | PCS | R20 R96 |
| 2 | 55.B0701.S20G | 63.15334.1DL | CHIP RES 15K J 1/16W 0402 | R2_SA;HF_SA;G_SA; | Released | TA-I;RALEC;CYNTEC;YAGEO;WALSIN | RM04JTN153 ; RTT02153JTH ; RR0510S-153-JN ; RC0402JR-0715KL;WR04X153JTL | Multiple |  | Purchase | SMT | 1 | PCS | PR150 |
| 2 | 55.B0701.S20G | 63.22534.1DL | CHIP RES 2.2M J 1/16W 0402 | R2_SA;HF_SA;G_SA; | Released | TAI;CYNTEC;YAGEO;RALEC | RM04JTN225;RR0510S-225-JN;RC0402JR-072M2L;RTT02225JTH | Multiple |  | Purchase | SMT | 1 | PCS | PR68 |
| 2 | 55.B0701.S20G | 63.24134.15L | CHIP RES 240 J 1/10W 0603 | R2_SA;HF_SA;G_SA; | Released | TA-I ; RALEC ; YAGEO | RM06JTN241 ; RTT03241JTP ; RC0603JR-07240RL | Multiple |  | Purchase | SMT | 2 | PCS | R260 R266 |
| 2 | 55.B0701.S20G | 63.2R233.15L | CHIP RES 2.2 J 1/10W 0603 | R2_SA;HF_SA;G_SA; | Released | TA-I ; RALEC ; YAGEO ; WALSIN | RM06JTN2R2 ; RTT032R2JTP ; RC0603JR-072R2L ; WR06X2R2JTL | Multiple |  | Purchase | SMT | 5 | PCS | PR209 R113 R132 R361 R60 |
| 2 | 55.B0701.S20G | 63.2R234.1DL | CHIP RES 2.2 J 1/16W 0402 | R2_SA;HF_SA;G_SA; | Released | TA-I;RALEC;CYNTEC;YAGEO;WALSIN | RM04JTN2R2 ; RTT022R2JTH ; RR-0510S-2R2-JN ; RC0402JR-072R2L;WR04X2R2JTL | Multiple |  | Purchase | SMT | 2 | PCS | R202 R221 |
| 2 | 55.B0701.S20G | 63.51534.1DL | CHIP RES 5.1M J 1/16W 0402 | R2_SA;HF_SA;G_SA; | Released | RALEC ; CYNTEC ; TA-I ; WALSIN ; YAGEO | RTT02515JTH ; RR0510S-515-JN ; RM04JTN515 ; WR04X515JTL ; RC0402JR-075M1L | Multiple |  | Purchase | SMT | 1 | PCS | PR208 |
| 2 | 55.B0701.S20G | 63.75334.1DL | CHIP RES 75K J 1/16W 0402 | R2_SA;HF_SA;G_SA; | Released | TA-I ; RALEC ; CYNTEC;YAGEO | RM04JTN753 ; RTT02753JTH ; RR-0510S-753-JN ; RC0402JR-0775KL | Multiple |  | Purchase | SMT | 1 | PCS | PR141 |
| 2 | 55.B0701.S20G | 63.R0031.16L | CHIP RES 0 J 1/8W 0805 | R2_SA;HF_SA;G_SA; | Released | TA-I ; RALEC ; YAGEO ; WALSIN | RM10JTN0 ; RTT05000JTP ; RC0805JR-070RL ; WR08X000PTL | Multiple |  | Purchase | SMT | 1 | PCS | PR79 |
| 2 | 55.B0701.S20G | 63.R0032.11L | CHIP RES 0 J 1/4W 1206 (ROHS) | R2_SA;HF_SA;G_SA; | Released | TA-I ; RALEC ; YAGEO; WALSIN | RM12JTN0 ; RTT06000JTP ; RC1206JR-070RL; WR12X000 PTL | Multiple |  | Purchase | SMT | 4 | PCS | PR191 PR194 PR221 PR31 |
| 2 | 55.B0701.S20G | 63.R0033.15L | CHIP RES 0 J 1/10W 0603 | R2_SA;HF_SA;G_SA; | Released | YAGEO;RALEC;TAI | RC0603JR-130RL;RTT03000JTP;RM06JTN0 | Multiple |  | Purchase | SMT | 12 | PCS | PR107 PR132 PR136 PR146 PR153 PR163 PR173 PR179 PR181 PR187 PR225 PR226 |
| 2 | 55.B0701.S20G | 63.R0034.1DL | CHIP RES 0 J 1/16W 0402 | R2_SA;HF_SA;G_SA; | Released | TA-I;RALEC;CYNTEC;YAGEO;WALSIN | RM04JTN0;RTT02000JTH;RR0510X-000-XN;RC0402JR-070RL;WR04X000PTL | Multiple |  | Purchase | SMT | 162 | PCS | PR108 PR11 PR113 PR119 PR123 PR124 PR128 PR129 PR131 PR133 PR134 PR137 PR142 PR143 PR152 PR154 PR157 PR158 PR160 PR162 PR165 PR166 PR171 PR178 PR180 PR182 PR189 PR20 PR205 PR21 PR217 PR219 PR22 PR220 PR23 PR3 PR35 PR37 PR38 PR4 PR41 PR42 PR43 PR44 PR45 PR47 PR48 PR49 PR5 PR62 PR63 PR67 PR71 PR72 PR74 PR75 PR8 PR82 PR84 PR85 PR89 PR99 R100 R104 R118 R120 R125 R128 R129 R133 R134 R135 R136 R142 R15 R165 R166 R174 R179 R180 R184 R189 R190 R191 R193 R194 R200 R201 R217 R218 R222 R223 R225 R226 R236 R238 R242 R249 R257 R259 R262 R264 R265 R268 R283 R288 R300 R302 R304 R307 R322 R324 R329 R340 R35 R352 R36 R37 R370 R382 R383 R384 R39 R391 R392 R393 R395 R396 R398 R4 R40 R404 R407 R411 R412 R413 R417 R435 R436 R442 R443 R460 R472 R473 R476 R48 R481 R482 R483 R49 R494 R50 R52 R54 R55 R56 R58 R61 R62 R8 R84 R97 |
| 2 | 55.B0701.S20G | 64.10005.55L | CHIP RES 100 F 1/10W 0603 | R2_SA;HF_SA;G_SA; | Released | TAI;RALEC;YAGEO | RM06FTN1000;RTT031000FTP;RC0603FR-07100RL | Multiple |  | Purchase | SMT | 5 | PCS | PR1 PR12 PR88 PR94 R245 |
| 2 | 55.B0701.S20G | 64.10005.6DL | CHIP RES 100 F 1/16W 0402 | R2_SA;HF_SA;G_SA; | Released | TA-I ; RALEC ; CYNTEC ; YAGEO;WALSIN | RM04FTN1000 ; RTT021000FTH ; RR0510S-1000-FN ; RC0402FR-07100RL;WR04X1000FTL | Multiple |  | Purchase | SMT | 18 | PCS | PR211 PR212 PR214 PR29 R160 R161 R203 R220 R23 R233 R237 R24 R281 R289 R374 R385 R386 R90 |
| 2 | 55.B0701.S20G | 64.10015.16L | CHIP RES 1K F 1/8W 0805(ROHS) | R2_SA;HF_SA;G_SA; | Released | YAGEO;RALEC;TAI | RC0805FR-071KL;RTT051001FTP;RM10FTN1001 | Multiple |  | Purchase | SMT | 1 | PCS | R1 |
| 2 | 55.B0701.S20G | 64.10015.6DL | CHIP RES 1K F 1/16W 0402 | R2_SA;HF_SA;G_SA; | Released | TA-I;RALEC;CYNTEC;YAGEO;WALSIN | RM04FTN1001 ; RTT021001FTH ; RR0510S-102-FN ; RC0402FR-071KL;WR04X1001FTL | Multiple |  | Purchase | SMT | 37 | PCS | PR2 PR93 R102 R103 R13 R14 R163 R239 R240 R241 R244 R248 R253 R255 R274 R275 R276 R280 R294 R32 R33 R336 R338 R342 R356 R360 R367 R378 R402 R42 R434 R471 R506 R79 R80 R83 R88 |
| 2 | 55.B0701.S20G | 64.10025.6DL | CHIP RES 10K F 1/16W 0402 | R2_SA;HF_SA;G_SA; | Released | TA-I;RALEC;CYNTEC;YAGEO;WALSIN | RM04FTN1002 ; RTT021002FTH ; RR0510S-103-FN ; RC0402FR-0710KL;WR04X1002FTL | Multiple |  | Purchase | SMT | 56 | PCS | PR110 PR138 PR155 PR172 PR177 PR19 PR196 PR199 PR207 PR216 PR218 PR222 PR24 PR46 PR50 PR51 PR65 PR7 PR90 PR91 R112 R121 R123 R130 R138 R139 R144 R146 R159 R164 R172 R177 R214 R224 R250 R323 R362 R375 R410 R439 R46 R477 R478 R484 R486 R496 R497 R503 R53 R63 R75 R76 R77 R78 R82 R94 |
| 2 | 55.B0701.S20G | 64.10026.6DL | CHIP RES 10K D 1/16W 0402 | R2_SA;HF_SA;G_SA; | Released | CYNTEC;RALEC;TA-I;WALSIN;YAGEO | RR0510Q-103-DN;RTT021002DTH;RM04DTN1002;WF04H1002DTL;RT0402DRE0710KL | Multiple |  | Purchase | SMT | 1 | PCS | PR106 |
| 2 | 55.B0701.S20G | 64.10035.6DL | CHIP RES 100K F 1/16W 0402 | R2_SA;HF_SA;G_SA; | Released | TA-I;RALEC;CYNTEC;YAGEO;WALSIN | RM04FTN1003 ; RTT021003FTH ; RR0510S-104-FN ; RC0402FR-07100KL;WR04X1003FTL | Multiple |  | Purchase | SMT | 3 | PCS | R162 R261 R333 |
| 2 | 55.B0701.S20G | 64.10045.55L | CHIP RES 1M F 1/10W 0603 | R2_SA;HF_SA;G_SA; | Released | TAI;RALEC;YAGEO;WALSIN | RM06FTN1004;RTT031004FTP;RC0603FR-071ML;WR06X1004FTL | Multiple |  | Purchase | SMT | 1 | PCS | R331 |
| 2 | 55.B0701.S20G | 64.10055.55L | CHIP RES 10M F 1/10W 0603 | R2_SA;HF_SA;G_SA; | Released | TA-I ; RALEC ; YAGEO | RM06FTN1005 ; RTT031005FTP ; RC0603FR-0710ML | Multiple |  | Purchase | SMT | 1 | PCS | R92 |
| 2 | 55.B0701.S20G | 64.10R05.55L | CHIP RES 10 F 1/10W 0603 | R2_SA;HF_SA;G_SA; | Released | TA-I;RALEC;YAGEO;WALSIN | RM06FTN10R0 ; RTT0310R0FTP ; RC0603FR-0710RL;WR06X10R0FTL | Multiple |  | Purchase | SMT | 3 | PCS | PR200 PR60 PR61 |
| 2 | 55.B0701.S20G | 64.10R05.6DL | CHIP RES 10 F 1/16W 0402 | R2_SA;HF_SA;G_SA; | Released | TA-I ; RALEC ; CYNTEC ; YAGEO | RM04FTN10R0 ; RTT0210R0FTH ; RR0510S-100-FN ; RC0402FR-0710RL | Multiple |  | Purchase | SMT | 7 | PCS | PR117 PR159 PR164 PR176 PR18 PR81 PR83 |
| 2 | 55.B0701.S20G | 64.10R75.6DL | CHIP RES 10.7 F 1/16W 0402 | R2_SA;HF_SA;G_SA; | Released | TA-I;RALEC;CYNTEC;YAGEO | RM04FTN10R7 ; RTT0210R7FTH ; RR0510S-10R7-FN ; RC0402FR-0710R7L | Multiple |  | Purchase | SMT | 3 | PCS | PR102 PR126 PR40 |
| 2 | 55.B0701.S20G | 64.11025.6DL | CHIP RES 11K F 1/16W 0402 | R2_SA;HF_SA;G_SA; | Released | TA-I ; RALEC ; CYNTEC ; YAGEO;WALSIN | RM04FTN1102 ; RTT021102FTH ; RR0510S-1102-FN ; RC0402FR-0711KL;WR04X1102FTL | Multiple |  | Purchase | SMT | 4 | PCS | PR17 PR210 PR73 R335 |
| 2 | 55.B0701.S20G | 64.1183D.55L | CHIP RES 118K B 1/10W 0603 | R2_SA;HF_SA;G_SA; | Released | TA-I;RALEC;YAGEO | RM06BTN1183;RTT031183BTP;RT0603BRD07118KL | Multiple |  | Purchase | SMT | 1 | PCS | PR184 |
| 2 | 55.B0701.S20G | 64.12005.55L | CHIP RES 120 F 1/10W 0603 | R2_SA;HF_SA;G_SA; | Released | TA-I ; RALEC ; YAGEO | RM06FTN1200 ; RTT031200FTP ; RC0603FR-07120RL | Multiple |  | Purchase | SMT | 2 | PCS | PR33 PR78 |
| 2 | 55.B0701.S20G | 64.12125.6DL | CHIP RES 12.1K F 1/16W 0402 | R2_SA;HF_SA;G_SA; | Released | TA-I ; RALEC ; CYNTEC ; YAGEO ; WALSIN | RM04FTN1212 ; RTT021212FTH ; RR0510S-1212-FN ; RC0402FR-0712K1L ; WR04X1212FTL | Multiple |  | Purchase | SMT | 2 | PCS | R208 R209 |
| 2 | 55.B0701.S20G | 64.13015.6DL | CHIP RES 1.3K F 1/16W 0402(ROH | R2_SA;HF_SA;G_SA; | Released | TAI;RALEC;CYNTEC;YAGEO | RM04FTN1301;RTT021301FTH;RR0510S-132-FN;RC0402FR-071K3L | Multiple |  | Purchase | SMT | 1 | PCS | PR28 |
| 2 | 55.B0701.S20G | 64.13725.6DL | CHIP RES 13.7K F 1/16W 0402 | R2_SA;HF_SA;G_SA; | Released | TA-I;RALEC;CYNTEC;YAGEO | RM04FTN1372;RTT021372FTH;RR0510S-1372-FN;RC0402FR-0713K7L | Multiple |  | Purchase | SMT | 1 | PCS | PR26 |
| 2 | 55.B0701.S20G | 64.14005.6DL | CHIP RES 140 F 1/16W 0402 | R2_SA;HF_SA;G_SA; | Released | TA-I ; RALEC ; CYNTEC ; YAGEO | RM04FTN1400 ; RTT021400FTH ; RR0510S-1400-FN ; RC0402FR-07140RL | Multiple |  | Purchase | SMT | 1 | PCS | PR69 |
| 2 | 55.B0701.S20G | 64.15005.55L | CHIP RES 150 F 1/10W 0603(ROHS | R2_SA;HF_SA;G_SA; | Released | TAI;RALEC;YAGEO;WALSIN | RM06FTN1500;RTT031500FTP;RC0603FR-07150RL;WR06X1500FTL | Multiple |  | Purchase | SMT | 2 | PCS | R500 R501 |
| 2 | 55.B0701.S20G | 64.15015.6DL | CHIP RES 1.5K F 1/16W 0402 | R2_SA;HF_SA;G_SA; | Released | TA-I;RALEC;CYNTEC;YAGEO;WALSIN | RM04FTN1501 ; RTT021501FTH ; RR0510S-152-FN ; RC0402FR-071K5L;WR04X1501FTL | Multiple |  | Purchase | SMT | 1 | PCS | PR14 |
| 2 | 55.B0701.S20G | 64.15025.6DL | CHIP RES 15K F 1/16W 0402 | R2_SA;HF_SA;G_SA; | Released | TA-I;RALEC;CYNTEC;YAGEO | RM04FTN1502;RTT021502FTH;RR0510S-153-FN;RC0402FR-0715KL | Multiple |  | Purchase | SMT | 2 | PCS | PR195 PR96 |
| 2 | 55.B0701.S20G | 64.15035.6DL | CHIP RES 150K F 1/16W 0402 | R2_SA;HF_SA;G_SA; | Released | TA-I;RALEC;CYNTEC;YAGEO;WALSIN | RM04FTN1503 ; RTT021503FTH ; RR0510S-154-FN ; RC0402FR-07150KL;WR04X1503FTL | Multiple |  | Purchase | SMT | 1 | PCS | R18 |
| 2 | 55.B0701.S20G | 64.15R05.6DL | CHIP RES 15 F 1/16W 0402 | R2_SA;HF_SA;G_SA; | Released | TA-I;RALEC;CYNTEC;YAGEO | RM04FTN15R0;RTT0215R0FTH;RR0510S-150-FN;RC0402FR-0715RL | Multiple |  | Purchase | SMT | 1 | PCS | R169 |
| 2 | 55.B0701.S20G | 64.16205.6DL | CHIP RES 162 F 1/16W 0402 | R2_SA;HF_SA;G_SA; | Released | TA-I ; RALEC ; CYNTEC ; YAGEO | RM04FTN1620 ; RTT021620FTH ; RR0510S-1620-FN ; RC0402FR-07162RL | Multiple |  | Purchase | SMT | 2 | PCS | R303 R350 |
| 2 | 55.B0701.S20G | 64.18005.6DL | CHIP RES 180 F 1/16W 0402(ROHS | R2_SA;HF_SA;G_SA; | Released | TAI;YAGEO;RALEC;CYNTEC | RM04FTN1800;RC0402FR-07180RL;RTT021800FTH;RR0510S-1800-FN | Multiple |  | Purchase | SMT | 1 | PCS | PR77 |
| 2 | 55.B0701.S20G | 64.19115.6DL | CHIP RES 1.91K F 1/16W 0402 | R2_SA;HF_SA;G_SA; | Released | TAI;RALEC;CYNTEC;YAGEO;WALSIN | RM04FTN1911;RTT021911FTH;RR0510S-1911-FN;RC0402FR-071K91L;WR04X1911FTL | Multiple |  | Purchase | SMT | 2 | PCS | PR36 PR55 |
| 2 | 55.B0701.S20G | 64.19626.6DL | CHIP RES 19.6K D 1/16W 0402 | R2_SA;HF_SA;G_SA; | Released | TA-I ; RALEC ; YAGEO | RM04DTN1962 ; RTT021962DTH ; RC0402DR-0719K6L | Multiple |  | Purchase | SMT | 1 | PCS | PR70 |
| 2 | 55.B0701.S20G | 64.20025.6DL | CHIP RES 20K F 1/16W 0402 | R2_SA;HF_SA;G_SA; | Released | TA-I;RALEC;CYNTEC;YAGEO;WALSIN | RM04FTN2002 ; RTT022002FTH ; RR0510S-203-FN ; RC0402FR-0720KL;WR04X2002FTL | Multiple |  | Purchase | SMT | 6 | PCS | PR144 PR168 PR169 PR53 PR59 R17 |
| 2 | 55.B0701.S20G | 64.20035.6DL | CHIP RES 200K F 1/16W 0402 | R2_SA;HF_SA;G_SA; | Released | TA-I;RALEC;CYNTEC;YAGEO;WALSIN | RM04FTN2003 ; RTT022003FTH ; RR0510S-204-FN ; RC0402FR-07200KL;WR04X2003FTL | Multiple |  | Purchase | SMT | 1 | PCS | PR6 |
| 2 | 55.B0701.S20G | 64.20045.6DL | CHIP RES 2M F 1/16W 0402 | R2_SA;HF_SA;G_SA; | Released | TA-I;RALEC;CYNTEC;YAGEO | RM04FTN2004;RTT022004FTH;RR0510S-2004-FN;RC0402FR-072ML | Multiple |  | Purchase | SMT | 1 | PCS | PR27 |
| 2 | 55.B0701.S20G | 64.22005.6DL | CHIP RES 220 F 1/16W 0402 | R2_SA;HF_SA;G_SA; | Released | TA-I;RALEC;CYNTEC;YAGEO | RM04FTN2200;RTT022200FTH;RR0510S-2200-FN;RC0402FR-07220RL | Multiple |  | Purchase | SMT | 1 | PCS | R291 |
| 2 | 55.B0701.S20G | 64.22015.6DL | CHIP RES 2.2K F 1/16W 0402 | R2_SA;HF_SA;G_SA; | Released | TA-I;RALEC;CYNTEC;YAGEO | RM04FTN2201;RTT022201FTH;RR0510S-222-FN;RC0402FR-072K2L | Multiple |  | Purchase | SMT | 7 | PCS | PR188 R116 R243 R319 R321 R495 R98 |
| 2 | 55.B0701.S20G | 64.22035.6DL | CHIP RES 220K F 1/16W 0402 | R2_SA;HF_SA;G_SA; | Released | TA-I;RALEC;CYNTEC;YAGEO | RM04FTN2203;RTT022203FTH;RR0510S-2203-FN;RC0402FR-07220KL | Multiple |  | Purchase | SMT | 1 | PCS | R405 |
| 2 | 55.B0701.S20G | 64.22115.6DL | CHIP RES 2.21K F 1/16W 0402 | R2_SA;HF_SA;G_SA; | Released | TA-I ; RALEC ; CYNTEC ; YAGEO | RM04FTN2211 ; RTT022211FTH ; RR0510S-2211-FN ; RC0402FR-072K21L | Multiple |  | Purchase | SMT | 1 | PCS | PR86 |
| 2 | 55.B0701.S20G | 64.22R05.6DL | CHIP RES 22 F 1/16W 0402(ROHS) | R2_SA;HF_SA;G_SA; | Released | TA-I;RALEC;CYNTEC;YAGEO | RM04FTN22R0;RTT0222R0FTH;RR0510S-220-FN;RC0402FR-0722RL | Multiple |  | Purchase | SMT | 2 | PCS | R292 R330 |
| 2 | 55.B0701.S20G | 64.23735.6DL | CHIP RES 237K F 1/16W 0402 | R2_SA;HF_SA;G_SA; | Released | TA-I ; RALEC ; CYNTEC ; YAGEO | RM04FTN2373 ; RTT022373FTH ; RR0510S-2373-FN ; RC0402FR-07237KL | Multiple |  | Purchase | SMT | 2 | PCS | PR151 PR183 |
| 2 | 55.B0701.S20G | 64.23R75.6DL | CHIP RES 23.7 F 1/16W 0402 | R2_SA;HF_SA;G_SA; | Released | TA-I;RALEC;CYNTEC;YAGEO | RM04FTN23R7;RTT0223R7FTH;RR0510S-23R7-FN;RC0402FR-0723R7L | Multiple |  | Purchase | SMT | 2 | PCS | R279 R380 |
| 2 | 55.B0701.S20G | 64.24905.6DL | CHIP RES 249 F 1/16W 0402 | R2_SA;HF_SA;G_SA; | Released | TAI;RALEC;CYNTEC;YAGEO | RM04FTN2490;RTT022490FTH;RR0510S-2490-FN;RC0402FR-07249RL | Multiple |  | Purchase | SMT | 1 | PCS | PR213 |
| 2 | 55.B0701.S20G | 64.26115.6DL | CHIP RES 2.61K F 1/16W 0402 | R2_SA;HF_SA;G_SA; | Released | TAI;RALEC;CYNTEC;YAGEO | RM04FTN2611;RTT022611FTH;RR0510S-2611-FN;RC0402FR-072K61L | Multiple |  | Purchase | SMT | 2 | PCS | PR215 PR95 |
| 2 | 55.B0701.S20G | 64.2R205.16L | CHIP RES 2.2 F 1/8W 0805 | R2_SA;HF_SA;G_SA; | Released | RALEC;TA-I;YAGEO | RTT052R20FTP;RM10FTN2R2;RC0805FR-072R2L | Multiple |  | Purchase | SMT | 1 | PCS | PR104 |
| 2 | 55.B0701.S20G | 64.30005.6DL | CHIP RES 300 F 1/16W 0402 | R2_SA;HF_SA;G_SA; | Released | CYNTEC;RALEC;TAI;YAGEO | RR0510S-301-FN;RTT023000FTH;RM04FTN3000;RC0402FR-07300RL | Multiple |  | Purchase | SMT | 15 | PCS | R131 R148 R149 R150 R151 R152 R153 R154 R155 R156 R305 R394 R400 R85 R89 |
| 2 | 55.B0701.S20G | 64.30015.6DL | CHIP RES 3K F 1/16W 0402 | R2_SA;HF_SA;G_SA; | Released | TA-I;RALEC;CYNTEC;YAGEO;WALSIN | RM04FTN3001;RTT023001FTH;RR0510S-302-FN;RC0402FR-073KL;WR04X3001FTL | Multiple |  | Purchase | SMT | 1 | PCS | R311 |
| 2 | 55.B0701.S20G | 64.30025.6DL | CHIP RES 30K F 1/16W 0402 | R2_SA;HF_SA;G_SA; | Released | TA-I;RALEC;CYNTEC;YAGEO;WALSIN | RM04FTN3002;RTT023002FTH;RR0510S-303-FN;RC0402FR-0730KL;WR04X3002FTL | Multiple |  | Purchase | SMT | 1 | PCS | R43 |
| 2 | 55.B0701.S20G | 64.30125.6DL | CHIP RES 30.1K F 1/16W 0402 | R2_SA;HF_SA;G_SA; | Released | TA-I ; RALEC ; CYNTEC ; YAGEO | RM04FTN3012 ; RTT023012FTH ; RR0510S-3012-FN ; RC0402FR-0730K1L | Multiple |  | Purchase | SMT | 1 | PCS | PR228 |
| 2 | 55.B0701.S20G | 64.30R15.6DL | CHIP RES 30.1 F 1/16W 0402 | R2_SA;HF_SA;G_SA; | Released | TA-I ; RALEC ; CYNTEC ; YAGEO | RM04FTN30R1 ; RTT0230R1FTH ; RR0510S-30R1-FN ; RC0402FR-0730R1L | Multiple |  | Purchase | SMT | 2 | PCS | R309 R381 |
| 2 | 55.B0701.S20G | 64.31625.6DL | CHIP RES 31.6K F 1/16W 0402 | R2_SA;HF_SA;G_SA; | Released | TA-I;RALEC;CYNTEC;YAGEO | RM04FTN3162;RTT023162FTH;RR0510S-3162-FN;RC0402FR-0731K6L | Multiple |  | Purchase | SMT | 1 | PCS | PR227 |
| 2 | 55.B0701.S20G | 64.33005.6DL | CHIP RES 330 F 1/16W 0402 | R2_SA;HF_SA;G_SA; | Released | CYNTEC;RALEC;TAI;YAGEO | RR0510S-331-FN;RTT023300FTH;RM04FTN3300;RC0402FR-07330RL | Multiple |  | Purchase | SMT | 1 | PCS | R263 |
| 2 | 55.B0701.S20G | 64.33015.55L | CHIP RES 3.3K F 1/10W 0603(ROH | R2_SA;HF_SA;G_SA; | Released | TAI;RALEC;YAGEO | RM06FTN3301;RTT033301FTP;RC0603FR-073K3L | Multiple |  | Purchase | SMT | 3 | PCS | PR167 PR64 R10 |
| 2 | 55.B0701.S20G | 64.33015.6DL | CHIP RES 3.3K F 1/16W 0402 | R2_SA;HF_SA;G_SA; | Released | TAI;RALEC;CYNTEC;YAGEO | RM04FTN3301;RTT023301FTH;RR0510S-332-FN;RC0402FR-073K3L | Multiple |  | Purchase | SMT | 2 | PCS | PR156 PR224 |
| 2 | 55.B0701.S20G | 64.33R05.6DL | CHIP RES 33 F 1/16W 0402 | R2_SA;HF_SA;G_SA; | Released | TA-I;RALEC;CYNTEC;YAGEO;WALSIN | RM04FTN33R0;RTT0233R0FTH;RR0510S-330-FN;RC0402FR-0733RL;WR04X33R0FTL | Multiple |  | Purchase | SMT | 30 | PCS | R101 R106 R109 R110 R115 R127 R16 R182 R188 R28 R286 R29 R290 R30 R31 R327 R328 R334 R349 R351 R354 R355 R368 R369 R376 R419 R420 R59 R65 R86 |
| 2 | 55.B0701.S20G | 64.34835.6DL | CHIP RES 348K F 1/16W 0402 | R2_SA;HF_SA;G_SA; | Released | TA-I;RALEC;CYNTEC;YAGEO | RM04FTN3483;RTT023483FTH;RR0510S-3483-FN;RC0402FR-07348KL | Multiple |  | Purchase | SMT | 1 | PCS | PR147 |
| 2 | 55.B0701.S20G | 64.36515.6DL | CHIP RES 3.65K F 1/16W 0402 | R2_SA;HF_SA;G_SA; | Released | CYNTEC ; RALEC ; TA-I ; YAGEO | RR0510S-3651-FN ; RTT023651FTH ; RM04FTN3651 ; RC0402FR-073K65L | Multiple |  | Purchase | SMT | 3 | PCS | PR148 PR16 PR98 |
| 2 | 55.B0701.S20G | 64.39015.6DL | CHIP RES 3.9K F 1/16W 0402 | R2_SA;HF_SA;G_SA; | Released | TA-I;RALEC;CYNTEC;YAGEO;WALSIN | RM04FTN3901;RTT023901FTH;RR0510S-3901-FN;RC0402FR-073K9L;WR04X3901FTL | Multiple |  | Purchase | SMT | 1 | PCS | PR192 |
| 2 | 55.B0701.S20G | 64.3R015.16L | CHIP RES 3.01 F 1/8W 0805 | R2_SA;HF_SA;G_SA; | Released | TA-I;RALEC | RM10FTN3R01;RTT053R01FTP | Multiple |  | Purchase | SMT | 2 | PCS | PR100 PR193 |
| 2 | 55.B0701.S20G | 64.40205.6DL | CHIP RES 402 F 1/16W 0402 | R2_SA;HF_SA;G_SA; | Released | TA-I;RALEC;CYNTEC;YAGEO | RM04FTN4020;RTT024020FTH;RR0510S-4020-FN;RC0402FR-07402RL | Multiple |  | Purchase | SMT | 4 | PCS | R282 R357 R364 R372 |
| 2 | 55.B0701.S20G | 64.40215.6DL | CHIP RES 4.02K F 1/16W 0402 | R2_SA;HF_SA;G_SA; | Released | TA-I;RALEC;CYNTEC;YAGEO;WALSIN | RM04FTN4021;RTT024021FTH;RR0510S-4021-FN;RC0402FR-074K02L;WR04X4021FTL | Multiple |  | Purchase | SMT | 1 | PCS | R254 |
| 2 | 55.B0701.S20G | 64.41215.6DL | CHIP RES 4.12K F 1/16W 0402 | R2_SA;HF_SA;G_SA; | Released | TA-I;RALEC;CYNTEC;YAGEO | RM04FTN4121;RTT024121FTH;RR0510S-4121-FN;RC0402FR-074K12L | Multiple |  | Purchase | SMT | 1 | PCS | PR139 |
| 2 | 55.B0701.S20G | 64.42215.6DL | CHIP RES 4.22K F 1/16W 0402 | R2_SA;HF_SA;G_SA; | Released | YAGEO;TA-I;CYNTEC;RALEC | RC0402FR-074K22L;RM04FTN4221;RR0510S-4221-FN;RTT024221FTH | Multiple |  | Purchase | SMT | 1 | PCS | PR186 |
| 2 | 55.B0701.S20G | 64.43205.6DL | CHIP RES 432 F 1/16W 0402 | R2_SA;HF_SA;G_SA; | Released | TAI;RALEC;CYNTEC;YAGEO | RM04FTN4320;RTT024320FTH;RR-0510S-4320-FN;RC0402FR-07432RL | Multiple |  | Purchase | SMT | 1 | PCS | R454 |
| 2 | 55.B0701.S20G | 64.43R25.6DL | CHIP RES 43.2 F 1/16W 0402 | R2_SA;HF_SA;G_SA; | Released | TA-I;RALEC;CYNTEC;YAGEO | RM04FTN43R2;RTT0243R2FTH;RR0510S-43R2-FN;RC0402FR-0743R2L | Multiple |  | Purchase | SMT | 10 | PCS | R418 R424 R425 R426 R427 R428 R429 R430 R431 R432 |
| 2 | 55.B0701.S20G | 64.44225.6DL | CHIP RES 44.2K F 1/16W 0402 | R2_SA;HF_SA;G_SA; | Released | TA-I;RALEC;CYNTEC;YAGEO;WALSIN | RTT024422FTH ; RR0510S-4422-FN ; RM04FTN4422 ; RC0402FR-0744K2L ; WR04X4422FTL | Multiple |  | Purchase | SMT | 1 | PCS | PR198 |
| 2 | 55.B0701.S20G | 64.45R35.6DL | CHIP RES 45.3 F 1/16W 0402 | R2_SA;HF_SA;G_SA; | Released | TA-I;RALEC;CYNTEC;YAGEO;WALSIN | RM04FTN45R3 ; RTT0245R3FTH ; RR0510S-45R3-FN ; RC0402FR-0745R3L ; WR04X45R3FTL | Multiple |  | Purchase | SMT | 1 | PCS | R299 |
| 2 | 55.B0701.S20G | 64.47015.6DL | CHIP RES 4.7K F 1/16W 0402 | R2_SA;HF_SA;G_SA; | Released | TA-I;RALEC;CYNTEC;YAGEO;WALSIN | RM04FTN4701;RTT024701FTH;RR0510S-472-FN;RC0402FR-074K7L;WR04X4701FTL | Multiple |  | Purchase | SMT | 74 | PCS | R105 R12 R124 R140 R141 R145 R157 R173 R178 R181 R185 R186 R195 R198 R228 R229 R232 R234 R26 R27 R3 R301 R306 R308 R310 R312 R313 R316 R318 R326 R341 R343 R363 R388 R390 R408 R409 R41 R415 R437 R438 R44 R441 R444 R445 R449 R451 R452 R455 R458 R459 R461 R465 R466 R467 R470 R474 R479 R485 R498 R499 R51 R57 R6 R64 R66 R67 R7 R70 R71 R74 R87 R91 R95 |
| 2 | 55.B0701.S20G | 64.47035.6DL | CHIP RES 470K F 1/16W 0402 | R2_SA;HF_SA;G_SA; | Released | TA-I;RALEC;CYNTEC;YAGEO;WALSIN | RM04FTN4703;RTT024703FTH;RR0510S-474-FN;RC0402FR-07470KL;WR04X4703FTL | Multiple |  | Purchase | SMT | 1 | PCS | PR15 |
| 2 | 55.B0701.S20G | 64.47515.6DL | CHIP RES 4.75K F 1/16W 0402 | R2_SA;HF_SA;G_SA; | Released | TA-I;RALEC;CYNTEC;YAGEO | RM04FTN4751;RTT024751FTH;RR0510S-4751-FN;RC0402FR-074K75L | Multiple |  | Purchase | SMT | 2 | PCS | PR185 PR223 |
| 2 | 55.B0701.S20G | 64.47535.6DL | CHIP RES 475K F 1/16W 0402 | R2_SA;HF_SA;G_SA; | Released | TA-I;RALEC;CYNTEC;YAGEO | RM04FTN4753;RTT024753FTH;RR0510S-4753-FN;RC0402FR-07475KL | Multiple |  | Purchase | SMT | 2 | PCS | PR118 PR204 |
| 2 | 55.B0701.S20G | 64.49915.6DL | CHIP RES 4.99K F 1/16W 0402 | R2_SA;HF_SA;G_SA; | Released | TA-I;RALEC;CYNTEC;YAGEO;WALSIN | RM04FTN4991 ; RTT024991FTH ; RR0510S-4991-FN ; RC0402FR-074K99L ; WR04X4991FTL | Multiple |  | Purchase | SMT | 1 | PCS | PR161 |
| 2 | 55.B0701.S20G | 64.49R95.6DL | CHIP RES 49.9 F 1/16W 0402 | R2_SA;HF_SA;G_SA; | Released | TA-I;RALEC;CYNTEC;YAGEO;WALSIN | RM04FTN49R9;RTT0249R9FTH;RR0510S-49R9-FN;RC0402FR-0749R9L;WR04X49R9FTL | Multiple |  | Purchase | SMT | 2 | PCS | R320 R34 |
| 2 | 55.B0701.S20G | 64.51015.6DL | CHIP RES 5.1K F 1/16W 0402 | R2_SA;HF_SA;G_SA; | Released | TA-I;RALEC;CYNTEC;YAGEO;WALSIN | RM04FTN5101 ; RTT025101FTH ; RR0510S-512-FN ; RC0402FR-075K1L;WR04X5101FTL | Multiple |  | Purchase | SMT | 1 | PCS | PR30 |
| 2 | 55.B0701.S20G | 64.51115.6DL | CHIP RES 5.11K F 1/16W 0402 | R2_SA;HF_SA;G_SA; | Released | TA-I ; RALEC ; CYNTEC ; YAGEO;WALSIN | RM04FTN5111 ; RTT025111FTH ; RR0510S-5111-FN ; RC0402FR-075K11L;WR04X5111FTL | Multiple |  | Purchase | SMT | 1 | PCS | PR140 |
| 2 | 55.B0701.S20G | 64.51R05.6DL | CHIP RES 51 F 1/16W 0402 | R2_SA;HF_SA;G_SA; | Released | TA-I;RALEC;CYNTEC;YAGEO;WALSIN | RM04FTN51R0;RTT0251R0FTH;RR0510S-510-FN;RC0402FR-0751RL;WR04X51R0FTL | Multiple |  | Purchase | SMT | 6 | PCS | R247 R251 R267 R269 R270 R277 |
| 2 | 55.B0701.S20G | 64.56015.6DL | CHIP RES 5.6K F 1/16W 0402(ROH | R2_SA;HF_SA;G_SA; | Released | TA-I;RALEC;CYNTEC;YAGEO;WALSIN | RM04FTN5601;RTT025601FTH;RR0510S-562-FN;RC0402FR-075K6L;WR04X5601FTL | Multiple |  | Purchase | SMT | 1 | PCS | PR76 |
| 2 | 55.B0701.S20G | 64.56R25.6DL | CHIP RES 56.2 F 1/16W 0402 | R2_SA;HF_SA;G_SA; | Released | TA-I;RALEC;CYNTEC;YAGEO | RM04FTN56R2;RTT0256R2FTH;RR0510S-56R2-FN;RC0402FR-0756R2L | Multiple |  | Purchase | SMT | 2 | PCS | R143 R293 |
| 2 | 55.B0701.S20G | 64.59015.6DL | CHIP RES 5.9K F 1/16W 0402 | R2_SA;HF_SA;G_SA; | Released | TA-I;RALEC;CYNTEC;YAGEO | RM04FTN5901;RTT025901FTH;RR0510S-5901-FN;RC0402FR-075K9L | Multiple |  | Purchase | SMT | 1 | PCS | PR34 |
| 2 | 55.B0701.S20G | 64.60415.6DL | CHIP RES 6.04K F 1/16W 0402 | R2_SA;HF_SA;G_SA; | Released | TA-I;RALEC;CYNTEC;YAGEO;WALSIN | RM04FTN6041;RTT026041FTH;RR0510S-6041-FN;RC0402FR-076K04L;WR04X6041FTL | Multiple |  | Purchase | SMT | 1 | PCS | PR125 |
| 2 | 55.B0701.S20G | 64.64916.6DL | CHIP RES 6.49K D 1/16W 0402 | R2_SA;HF_SA;G_SA; | Released | RALEC ; CYNTEC ; TA-I ; YAGEO | RTT026491DTH ; RR0510Q-6491-DN ; RM04DTN6491 ; RT0402DRE076K49L | Multiple |  | Purchase | SMT | 1 | PCS | PR103 |
| 2 | 55.B0701.S20G | 64.73225.6DL | CHIP RES 73.2K F 1/16W 0402 | R2_SA;HF_SA;G_SA; | Released | TA-I;RALEC;CYNTEC;YAGEO;WALSIN | RM04FTN7322;RTT027322FTH;RR0510S-7322-FN;RC0402FR-0773K2L;WR04X7322FTL | Multiple |  | Purchase | SMT | 1 | PCS | PR202 |
| 2 | 55.B0701.S20G | 64.78705.6DL | CHIP RES 787 F 1/16W 0402 | R2_SA;HF_SA;G_SA; | Released | RALEC;CYNTEC;TA-I;WALSIN;YAGEO | RTT027870FTH;RR0510S-7870-FN;RM04FTN7870;WR04X7870FTL;RC0402FR-07787RL | Multiple |  | Purchase | SMT | 1 | PCS | PR121 |
| 2 | 55.B0701.S20G | 64.78715.6DL | CHIP RES 7.87K F 1/16W 0402 | R2_SA;HF_SA;G_SA; | Released | TA-I;RALEC;CYNTEC;YAGEO | RM04FTN7871;RTT027871FTH;RR0510S-7871-FN;RC0402FR-077K87L | Multiple |  | Purchase | SMT | 1 | PCS | PR66 |
| 2 | 55.B0701.S20G | 64.78725.6DL | CHIP RES 78.7K F 1/16W 0402 | R2_SA;HF_SA;G_SA; | Released | TA-I;RALEC;CYNTEC;YAGEO | RM04FTN7872;RTT027872FTH;RR0510S-7872-FN;RC0402FR-0778K7L | Multiple |  | Purchase | SMT | 1 | PCS | PR116 |
| 2 | 55.B0701.S20G | 64.82015.6DL | CHIP RES 8.2K F 1/16W 0402 | R2_SA;HF_SA;G_SA; | Released | TAI;RALEC;CYNTEC;YAGEO | RM04FTN8201;RTT028201FTH;RR0510S-822-FN;RC0402FR-078K2L | Multiple |  | Purchase | SMT | 2 | PCS | R468 R69 |
| 2 | 55.B0701.S20G | 64.84515.6DL | CHIP RES 8.45K F 1/16W 0402 | R2_SA;HF_SA;G_SA; | Released | TA-I;RALEC;CYNTEC;YAGEO | RM04FTN8451;RTT028451FTH;RR0510S-8451-FN;RC0402FR-078K45L | Multiple |  | Purchase | SMT | 1 | PCS | PR145 |
| 2 | 55.B0701.S20G | 65.B07ZZ.054 | HONEY BADGER PANTHER+ DVT2 FPGA MODULE | N/A; | Released |  |  |  | E | Manufacture | SMT | 1 | PCS | DUMMY |
| 3 | 65.B07ZZ.054 | 53.B0707.021 | FW FPGA E06 FLASH | R2; | Released | TBD |  | Single |  | Manufacture |  | 1 | PCS |  |
| 3 | 65.B07ZZ.054 | 72.25Q64.A03 | IC FALSH MEM W25Q64FVZPIG WSON 8P | R2_C;HF_C; | Released | WINBOND | W25Q64FVZPIG | Single |  | Purchase | SMT | 1 | PCS | U17 |
| 2 | 55.B0701.S20G | 68.00084.771 | CHIP BEAD BLM41PG600SN1L MURAT | R2_SA; | Released | MURATA | BLM41PG600SN1L | Single |  | Purchase | SMT | 1 | PCS | PL7 |
| 2 | 55.B0701.S20G | 68.00084.831 | CHIP BEAD BLM21PG220SN1D (LF) | R2_SA;HF_SA; | Released | MURATA | BLM21PG220SN1D | Single |  | Purchase | SMT | 1 | PCS | PL9 |
| 2 | 55.B0701.S20G | 68.00084.A31 | CHIP BEAD BLM18PG121SN1D 0603 | R2_SA;HF_SA;G_SA; | Released | MURATA | BLM18PG121SN1D | Single |  | Purchase | SMT | 6 | PCS | L4 L5 L6 L7 L8 L9 |
| 2 | 55.B0701.S20G | 68.00143.041 | CHIP BEAD BLM18PG330SN1D MURAT | R2_SA;HF_SA;G_SA; | Released | MURATA | BLM18PG330SN1D | Single |  | Purchase | SMT | 9 | PCS | L1 L10 L11 L12 L13 L14 L2 L3 PL8 |
| 2 | 55.B0701.S20G | 68.1R010.20C | CHIP CHOKE 1.0UH MPLCG0630L1R0 | R2_SA;HF_SA; | Released | NEC;TOKIN | MPLCG0630L1R0 | Multiple |  | Purchase | SMT | 1 | PCS | PL1 |
| 2 | 55.B0701.S20G | 68.2R21B.10J | CHIP IND 2.2UH MMD-06CZ-2R2M-V | R2_SA;HF_SA;G_SA; | Released | MAGLAYER | MMD-06CZ-2R2M-V1W | Single |  | Purchase | SMT | 1 | PCS | PL6 |
| 2 | 55.B0701.S20G | 68.3012N.10C | CHIP IND 300NH FP1007R3-R30-R | R2_SA; | Released | COOPER | FP1007R3-R30-R | Single |  | Purchase | SMT | 2 | PCS | PL2 PL4 |
| 2 | 55.B0701.S20G | 68.R2210.201 | CHIP CHOCK0.22U PCMB042T-R22MS | R2_SA; | Released | CYNTEC | PCMB042T-R22MS | Single |  | Purchase | SMT | 1 | PCS | PL3 |
| 2 | 55.B0701.S20G | 68.R6810.20J | CHIP CHOKE 0.68UH PCMB063T-R68MS | R2_SA;HF_SA; | Released | CYNTEC | PCMB063T-R68MS | Single |  | Purchase | SMT | 1 | PCS | PL5 |
| 2 | 55.B0701.S20G | 69.60011.121 | THERM SMD 10K NCP15XH103F03RC | R2_SA;HF_SA; | Released | MURATA | NCP15XH103F03RC | Single |  | Purchase | SMT | 1 | PCS | PRT1 |
| 2 | 55.B0701.S20G | 69.60013.201 | THERM 100K TSM0B104F4251RZ 0402 SMD | R2_SA;HF_SA;G_SA; | Released | TKS | TSM0B104F4251RZ | Single |  | Purchase | SMT | 1 | PCS | PRT2 |
| 2 | 55.B0701.S20G | 71.09833.00W | IC BUF 9DB833AGILFT TSSOP 48P | R2_SA; | Released | IDT | 9DB833AGILFT | Single |  | Purchase | SMT | 1 | PCS | U28 |
| 2 | 55.B0701.S20G | 71.18602.00W | IC I2C BUS SC18IS602BIPW TSSOP | R2_SA; | Released | NXP | SC18IS602BIPW | Single |  | Purchase | SMT | 1 | PCS | U48 |
| 2 | 55.B0701.S20G | 72.24128.G01 | IC EEPRM M24128-BWMN6TP SO8 | R2_SA;HF_SA;G_SA; | Released | ST | M24128-BWMN6TP | Single |  | Purchase | SMT | 1 | PCS | U22 |
| 2 | 55.B0701.S20G | 72.25256.E01 | IC EEPROM AT25256B-SSHL-T SOIC | R2_SA; | Released | ATMEL | AT25256B-SSHL-T | Single |  | Purchase | SMT | 1 | PCS | U21 |
| 2 | 55.B0701.S20G | 73.01G07.01H | IC BUF SN74LVC1G07DCKRG4 DCK5P | R2_SA; | Released | TI | SN74LVC1G07DCKRG4 | Single |  | Purchase | SMT | 2 | PCS | U31 U4 |
| 2 | 55.B0701.S20G | 73.01G08.L03 | IC CMOS SN74LVC1G08DCKR SC-70 | R2_SA;HF_SA;G_SA; | Released | TI | SN74LVC1G08DCKR | Single |  | Purchase | SMT | 1 | PCS | U15 |
| 2 | 55.B0701.S20G | 73.01G11.AHH | IC CMOS SN74LVC1G11DCKR DCK | R_SA;G_SA; | Released | TI | SN74LVC1G11DCKR | Single |  | Purchase | SMT | 2 | PCS | U42 U43 |
| 2 | 55.B0701.S20G | 73.01G14.L05 | IC CMOS 74LVC1G14DCKR SC-70(GP | R2_SA;G_SA; | Released | TI | SN74LVC1G14DCKR | Single |  | Purchase | SMT | 5 | PCS | U10 U12 U2 U6 U7 |
| 2 | 55.B0701.S20G | 73.01G17.BHH | IC CMOS SN74LVC1G17DCKR DCK 5P | R2_SA;HF_SA; | Released | TI | SN74LVC1G17DCKR | Single |  | Purchase | SMT | 2 | PCS | U45 U46 |
| 2 | 55.B0701.S20G | 73.03257.003 | IC CMOS SN74CBTLV3257RGYR QFN | R2_SA; | Released | TI | SN74CBTLV3257RGYR | Single |  | Purchase | SMT | 1 | PCS | U50 |
| 2 | 55.B0701.S20G | 73.1G126.DHG | IC CMOS SN74LVC1G126DCKR SC70 | R2_SA;HF_SA; | Released | TI | SN74LVC1G126DCKR | Single |  | Purchase | SMT | 3 | PCS | U39 U40 U41 |
| 2 | 55.B0701.S20G | 74.00075.B79 | IC TEMP SENSOR TMP75AIDGKR MSOP 8P | R2_SA; | Released | TI | TMP75AIDGKR | Single |  | Purchase | SMT | 1 | PCS | U1 |
| 2 | 55.B0701.S20G | 74.00321.X1F | IC OP LMV321IDCKR SC70 5P | R2_SA;HF_SA; | Released | TI | LMV321IDCKR | Single |  | Purchase | SMT | 2 | PCS | U23 U27 |
| 2 | 55.B0701.S20G | 74.00538.073 | IC PWM EP53F8QI-T QFN 16P | R2_SA; | Released | ALTERA | EP53F8QI-T | Single |  | Purchase | SMT | 2 | PCS | PU11 PU13 |
| 2 | 55.B0701.S20G | 74.06337.073 | IC PWM EN6337QI QFN 38P | R2_SA; | Released | ALTERA | EN6337QI | Single |  | Purchase | SMT | 1 | PCS | PU1 |
| 2 | 55.B0701.S20G | 74.06353.A73 | IC PWM ISL6353CRTZ TQFN 40P(REV.VS11) | R2_SA; | Released | INTERSIL | ISL6353CRTZ | Single |  | Purchase | SMT | 1 | PCS | PU10 |
| 2 | 55.B0701.S20G | 74.07828.A4G | IC CONV ADS7828E/2K5 TSSOP 16P | R2_SA; | Released | TI | ADS7828E/2K5 | Single |  | Purchase | SMT | 1 | PCS | U19 |
| 2 | 55.B0701.S20G | 74.23157.A99 | IC A.S TS5A23157DGSR DGS 10P | R2_SA;G_SA; | Released | TI | TS5A23157DGSR | Single |  | Purchase | SMT | 1 | PCS | U33 |
| 2 | 55.B0701.S20G | 74.51200.071 | IC TERM REGU TPS51200 SON 10P | R2_SA; | Released | TI | TPS51200 | Single |  | Purchase | SMT | 2 | PCS | PU12 PU4 |
| 2 | 55.B0701.S20G | 74.53318.073 | IC PWR CTRL TPS53318DQPR QFN 22P | R2_SA;HF_SA; | Released | TI | TPS53318DQPR | Single |  | Purchase | SMT | 1 | PCS | PU15 |
| 2 | 55.B0701.S20G | 74.53319.073 | IC PWR CTRL TPS53319DQPR QFN 22P | R2_SA;HF_SA; | Released | TI | TPS53319DQPR | Single |  | Purchase | SMT | 1 | PCS | PU7 |
| 2 | 55.B0701.S20G | 74.74801.A33 | IC LDO TPS74801RGW QFN 20P | R2_SA; | Released | TI | TPS74801RGW | Single |  | Purchase | SMT | 2 | PCS | PU14 PU16 |
| 2 | 55.B0701.S20G | 74.79301.07P | IC LDO TPS79301DBVR SOT-23-6 | R2_SA; | Released | TI | TPS79301DBVR | Single |  | Purchase | SMT | 1 | PCS | PU17 |
| 2 | 55.B0701.S20G | 74.90727.B7P | IC XDCP ISL90727WIE627Z-TK SC-70 6P | R2_SA;HF_SA; | Obsoleted | INTERSIL | ISL90727WIE627Z-TK | Single |  | Purchase | SMT | 1 | PCS | U26 |
| 2 | 55.B0701.S20G | 74.95831.B73 | IC V.R ISL95831CHRTZ-TS2568 TQFN 48P | R2_SA; | Released | INTERSIL | ISL95831CHRTZ-TS2568 | Single |  | Purchase | SMT | 1 | PCS | PU3 |
| 2 | 55.B0701.S20G | 74.D1117.G3C | IC A.R LD1117AG-12-SOT-223 | R2_SA;HF_SA;G_SA; | Released | UTC | LD1117AG-12-AA3-A-R | Single |  | Purchase | SMT | 2 | PCS | PU8 PU9 |
| 2 | 55.B0701.S20G | 75.00054.E7D | IC DIODE S.B BAT54C-7-F SOT-23 3P | R2_SA;HF_SA;G_SA; | Released | DIODES | BAT54C-7-F | Single |  | Purchase | SMT | 1 | PCS | D1 |
| 2 | 55.B0701.S20G | 75.04253.075 | IC MOSFET IRFH4253DTRPBF PQFN 8P | R2_SA; | Released | IR | IRFH4253DTRPBF | Single |  | Purchase | SMT | 2 | PCS | PU2 PU6 |
| 2 | 55.B0701.S20G | 78.10134.1FL | CHIP CAP C 100P 50V J0402 NPO | R2_SA;HF_SA;G_SA; | Released | AVX;DARFON;MURATA;PHYCOMP;SAMSUNG;TAIYO;TDK;WALSIN;YAGEO | CM05CG101J50AH;C1005NP0101JGT;GRM1555C1H101JA01D;223886915101;CL05C101JB5NNNC;UMK105CH101JV-F;C1005C0G1H101JT;0402N101J500LT;CC0402JRNPO9BN101 | Multiple |  | Purchase | SMT | 2 | PCS | PC1 PC147 |
| 2 | 55.B0701.S20G | 78.10224.2FL | CHIP CAP C 1000P 50V K0402 X7R | R2_SA;HF_SA;G_SA; | Released | AVX;DARFON;MURATA;PHYCOMP;SAMSUNG;TAIYO;TDK;MURATA;AVX;YAGEO | CM05X7R102K50AH;C1005X7R102KGT;GRM155R71H102KA01D;223858715623;CL05B102KB5NNNC;UMK105BJ102KV-F;C1005X7R1H102KT000F;WBM155R71H102KA01D;04025C102KAT2A;CC0402KRX7R9BB102 | Multiple |  | Purchase | SMT | 12 | PCS | PC103 PC108 PC115 PC174 PC22 PC3 PC43 PC57 PC72 PC75 PC97 PC99 |
| 2 | 55.B0701.S20G | 78.10321.2FL | CHIP CAP C 0.01U 16V K0402 X7R | R2_SA;HF_SA;G_SA; | Released | AVX;DARFON;MURATA;PHYCOMP;SAMSUNG;TAIYO;TDK;WALSIN;MURATA;YAGEO | 0402YC103KAT2A;C1005X7R103KET;GRM155R71C103KA01D;223878715636;CL05B103KO5NNNC;EMK105BJ103KV-F;C1005X7R1C103KT000F;0402B103K160CT;WBM155R71C103KA01D;CC0402KRX7R7BB103 | Multiple |  | Purchase | SMT | 15 | PCS | C282 C283 C305 C306 C307 C308 C45 C48 C56 C58 C60 C64 PC14 PC211 PC79 |
| 2 | 55.B0701.S20G | 78.10421.2FL | CHIP CAP C 0.1U 16V K0402 X7R | R2_SA;HF_SA;G_SA; | Released | DARFON;MURATA;PHYCOMP;SAMSUNG;TAIYO;TDK;WALSIN;YAGEO | C1005X7R104KET;GRM155R71C104KA88D;223878715649;CL05B104KO5NNNC;EMK105BJ104KV-FR ;C1005X7R1C104KT000F;0402B104K160CT;CC0402KRX7R7BB104 | Multiple |  | Purchase | SMT | 91 | PCS | C107 C109 C120 C121 C127 C170 C173 C177 C183 C2 C200 C230 C231 C248 C249 C262 C263 C264 C265 C266 C267 C268 C269 C270 C271 C272 C273 C274 C275 C276 C277 C278 C279 C280 C281 C284 C285 C286 C287 C294 C295 C296 C303 C304 C311 C324 C325 C326 C327 C328 C329 C330 C331 C332 C333 C334 C340 C341 C342 C343 C344 C348 C349 C350 C351 C356 C358 C4 C69 C70 C71 C77 C78 C79 C83 C84 C85 C86 C93 C94 C95 PC114 PC125 PC128 PC190 PC195 PC205 PC53 PC54 PC63 PC9 |
| 2 | 55.B0701.S20G | 78.10422.2FL | CHIP CAP C 0.1U 25V K0402 X7R | R2_SA;HF_SA;G_SA; | Released | YAGEO;WALSIN;MURATA;TDK | CC0402KRX7R8BB104;0402B104K250CT;GRM155R71E104KE14D;C1005X7R1E104KT | Multiple |  | Purchase | SMT | 8 | PCS | C80 PC150 PC152 PC181 PC32 PC33 PC82 PC95 |
| 2 | 55.B0701.S20G | 78.10423.2FL | CHIP CAP C 0.1U 10V K0402 X7R | R2_SA;HF_SA;G_SA; | Released | MURATA;PHYCOMP;SAMSUNG;TAIYO;TDK;DARFON;WALSIN;MURATA;YAGEO | GRM155R71A104KA01D;223824715649;CL05B104KP5NNNC;RMLMK105BJ104KV-F;C1005X7R1A104KT000F;C1005X7R104KDT;0402B104K100CT;WBM155R71A104KA01D;CC0402KRX7R6BB104 | Multiple |  | Purchase | SMT | 64 | PCS | C10 C11 C12 C13 C134 C135 C136 C138 C139 C140 C144 C149 C15 C162 C164 C165 C172 C18 C192 C197 C201 C206 C207 C208 C209 C21 C223 C23 C232 C233 C234 C235 C236 C25 C27 C28 C29 C309 C310 C314 C317 C323 C335 C336 C337 C338 C339 C35 C41 C46 C49 C51 C52 C54 C6 C61 C62 C72 C73 C74 C8 C82 PC138 PC203 |
| 2 | 55.B0701.S20G | 78.10424.2BL | CHIP CAP C 0.1U 50V K0603 X7R | R2_SA;HF_SA;G_SA; | Released | MURATA;TDK;AVX;PHYCOMP;SAMSUNG;DARFON;MATSUKI;WALSIN | GRM188R71H104KA93D;C1608X7R1H104KT000N;06035C104KAT2A;223858615649;CL10B104KB8NNNC;C1608X7R104KGT;MAG03X7R1H104K;0603B104K500CT | Multiple |  | Purchase | SMT | 3 | PCS | PC164 PC50 PC78 |
| 2 | 55.B0701.S20G | 78.10431.2FL | CHIP CAP 0.1UF J 16V 0402 X7R | R2_SA;HF_SA;G_SA; | Released | KEMET;TDK;MURATA;PHYCOMP;DARFON;SAMSUNG;WALSIN | C0402C104J4RAC;C1005X7R1C104JT;GRM155R71C104JA88D;223878715549;C1005X7R104JET;CL05B104JO5NNNC;0402B104J160CT | Multiple |  | Purchase | SMT | 3 | PCS | C143 C154 C257 |
| 2 | 55.B0701.S20G | 78.10520.2BL | CHIP CAP C 1U 6.3V K0603 X7R | R2_SA;HF_SA;G_SA; | Released | MURATA;TAIYO;DARFON;WALSIN;PHYCOMP;SAMSUNG | GRM188R70J105K;JMK107B7105KA-T;C1608X7R105KCT;0603B105K6R3CT;225520615663;CL10B105KQ8NNNC | Multiple |  | Purchase | SMT | 5 | PCS | C352 C353 C354 C355 C357 |
| 2 | 55.B0701.S20G | 78.10520.5FL | CHIP CAP C 1U 6.3V K0402 X5R | R2_SA;HF_SA;G_SA; | Released | TDK;TAIYO;PHYCOMP;DARFON;MURATA;SAMSUNG;MATSUKI;WALSIN;YAGEO;AVX | C1005X5R0J105KT;JMK105BJ105KV-F;225520713663;C1005X5R105KCT;GRM155R60J105KE19D;CL05A105KQ5NNNC;MAG02X5R0J105K;0402X105K6R3CT;CC0402KRX5R5BB105;CM05X5R105K06AT | Multiple |  | Purchase | SMT | 13 | PCS | C102 C137 C247 C250 C291 C30 C302 C31 C87 C92 C96 C98 PC209 |
| 2 | 55.B0701.S20G | 78.10521.2BL | CHIP CAP C 1U 16V K0603 X7R | R2_SA;HF_SA;G_SA; | Released | KEMET;MURATA;TAIYO;TDK;PHYCOMP;WALSIN;SAMSUNG;DARFON | C0603C105K4RAC;GRM188R71C105KA12D;EMK107B7105KA-T;C1608X7R1C105KT;223878615663;0603B105K160CT;CL10B105KO8NNNC;C1608X7R105KET | Multiple |  | Purchase | SMT | 6 | PCS | PC106 PC110 PC127 PC35 PC65 PC93 |
| 2 | 55.B0701.S20G | 78.10521.5FL | CHIP CAP C 1U 16V K0402 X5R | R2_SA;HF_SA;G_SA; | Released | TAIYO;AVX;SAMSUNG;DARFON;MURATA | EMK105BJ105KV-F;CV05X5R105K16AH;CL05A105KO5NNNC;C1005X5R105KET;GRM155R61C105KA12D | Multiple |  | Purchase | SMT | 1 | PCS | PC89 |
| 2 | 55.B0701.S20G | 78.10522.2BL | CHIP CAP C 1U 25V K0603 X7R | R2_SA;HF_SA;G_SA; | Released | MURATA;TAIYO;TDK;WALSIN;SAMSUNG;DARFON | GRM188R71E105KA12D;TMK107BJ105KA-T;C1608X7R1E105KT;CL10B105KA8NNNC;C1608X7R105KFT | Multiple |  | Purchase | SMT | 5 | PCS | C119 C16 C20 C227 C258 |
| 2 | 55.B0701.S20G | 78.10523.5FL | CHIP CAP C 1U 10V K0402 X5R | R2_SA;HF_SA;G_SA; | Released | MURATA;TDK;DARFON;MATSUKI;PHYCOMP;TAIYO;SAMSUNG;WALSIN | GRM155R61A105KE15D;C1005X5R1A105KT;C1005X5R105KDT;MAG02X5R1A105K;223824713663;LMK105BJ105KVF;CL05A105KP5NNNC;0402X105K100CT | Multiple |  | Purchase | SMT | 83 | PCS | C101 C114 C118 C123 C124 C128 C129 C130 C131 C132 C133 C14 C142 C145 C146 C147 C148 C150 C151 C152 C153 C155 C156 C157 C160 C163 C166 C167 C169 C171 C174 C175 C176 C178 C180 C182 C186 C187 C190 C193 C194 C195 C198 C202 C203 C204 C211 C212 C213 C215 C216 C217 C218 C219 C22 C220 C221 C224 C225 C226 C228 C229 C237 C238 C239 C240 C241 C242 C243 C245 C246 C252 C253 C254 C256 C259 C261 C297 C299 C76 C99 PC185 PC8 |
| 2 | 55.B0701.S20G | 78.10610.5BL | CHIP CAP C 10U 6.3V M0603 X5R | R2_SA;HF_SA;G_SA; | Released | DARFON;MATSUKI;MURATA;PHYCOMP;SAMSUNG;TAIYO;TDK;AVX;YAGEO | C1608X5R106MCT;MAG03X5R0J106M;GRM188R60J106ME47D;225520613776;CL10A106MQ8NNNC;JMK107BJ106MA-T;C1608X5R0J106MT0A0E;CV105X5R106M06AT;CC0603MRX5R5BB106 | Multiple |  | Purchase | SMT | 52 | PCS | C100 C103 C104 C105 C106 C108 C110 C111 C112 C116 C117 C24 C255 C288 C289 C290 C292 C293 C298 C300 C301 C36 C43 C53 C67 C68 C90 C91 C97 PC117 PC118 PC119 PC140 PC142 PC143 PC146 PC153 PC154 PC156 PC158 PC167 PC168 PC169 PC178 PC179 PC204 PC206 PC207 PC208 PC45 PC49 PC52 |
| 2 | 55.B0701.S20G | 78.10620.21L | CHIP CAP C 10U 6.3V K0805 X7R | R2_SA;HF_SA;G_SA; | Released | MURATA;TAIYO;DARFON;AVX KYOCERA | GRM21BR70J106K;JMK212B7106KG-T;C2012X7R106KC; CM21X7R106K06AT | Multiple |  | Purchase | SMT | 18 | PCS | C158 C159 PC129 PC130 PC133 PC134 PC139 PC141 PC196 PC198 PC199 PC200 PC201 PC202 PC21 PC26 PC88 PC98 |
| 2 | 55.B0701.S20G | 78.10621.22L | CHIP CAP C 10U 16V K1206 X7R | R2_SA;HF_SA;G_SA; | Released | MURATA;TDK;AVX;DARFON;SAMSUNG;TAIYO | GRM31CR71C106KA12L;C3216X7R1C106KT;CM316X7R106K16AT;C3216X7R106KEP;CL31B106KOHNNNE;EMK316B7106KL-T | Multiple |  | Purchase | SMT | 2 | PCS | PC111 PC62 |
| 2 | 55.B0701.S20G | 78.10622.51L | CHIP CAP C 10U 25V K0805 X5R | R2_SA;HF_SA;G_SA; | Released | MATSUKI;SUMSUNG;TAIYO;AVX;MURATA;TDK | MAG05X5R1E106K ; CL21A106KAYNNNE ; TMK212BJ106KG-TD;CM21X5R106K25AT;GRM21BR61E106KA73L;C2012X5R1E106KT | Multiple |  | Purchase | SMT | 6 | PCS | C39 PC165 PC175 PC18 PC20 PC23 |
| 2 | 55.B0701.S20G | 78.10710.52L | CHIP CAP C 100U 6.3V M1206 X5R | R2_SA;HF_SA;G_SA; | Released | MURATA;TAIYO | GRM31CR60J107ME39L;JMK316BJ107ML | Multiple |  | Purchase | SMT | 3 | PCS | PC73 PC77 PC80 |
| 2 | 55.B0701.S20G | 78.10710.53L | CHIP CAP C 100U 6.3V M1210 X5R | R2_SA;HF_SA;G_SA; | Released | MURATA;TAIYO;TDK;KEMET;TAIYO;SAMSUNG | GRM32ER60J107ME20L;JMK325BJ107MM-T;C3225X5R0J107MT000N;C1210C107M9PAC;JMK325ABJ107MM-P;CL32A107MQVNNNE | Multiple |  | Purchase | SMT | 2 | PCS | PC157 PC180 |
| 2 | 55.B0701.S20G | 78.15044.1FL | CHIP CAP C 15P 50V G0402 NPO | R2_SA;HF_SA;G_SA; | Released | DARFON;MURATA;PHYCOMP | C1005NP0150GGT;GRM1555C1H150GA01D;223886914159 | Multiple |  | Purchase | SMT | 1 | PCS | PC4 |
| 2 | 55.B0701.S20G | 78.15124.2FL | CHIP CAP C 150P 50V K0402 X7R | R2_SA;HF_SA;G_SA; | Released | AVX;PHYCOMP;DARFON | 04025C151KAT2A;223858715612;C1005X7R151KGT | Multiple |  | Purchase | SMT | 1 | PCS | PC58 |
| 2 | 55.B0701.S20G | 78.15224.2FL | CHIP CAP C 1500P 50V K0402 X7R | R2_SA;HF_SA;G_SA; | Released | MURATA;AVX;TDK;TAYIO;PHYCOMN;DARFON;WALSIN | GRM155R71H152KA01D;04025C152KAT2A;C1005X7R1H152KT000F;UMK105BJ152KV-F;223858715625;C1005X7R152KGT;0402B152K500CT | Multiple |  | Purchase | SMT | 1 | PCS | PC192 |
| 2 | 55.B0701.S20G | 78.15322.2FL | CHIP CAP C 0.015U 25V K0402 X7R | R2_SA;HF_SA;G_SA; | Released | MURATA;TDK;WALSIN;DARFON;PHYCOMP | GRM155R71E153KA61D;C1005X7R1E153KT000F;0402B153K250CT;C1005X7R153KFT;223891715638 | Multiple |  | Purchase | SMT | 1 | PCS | PC122 |
| 2 | 55.B0701.S20G | 78.22044.1FL | CHIP CAP C 22P 50V G0402 NPO | R2_SA;HF_SA;G_SA; | Released | DARFON ; PHYCOMP ; YAGEO ; WALSIN | C1005NP0220GGT ; 223886914229 ; CC0402GRNPO9BN220 ; 0402N220G500CT | Multiple |  | Purchase | SMT | 1 | PCS | PC210 |
| 2 | 55.B0701.S20G | 78.22124.2FL | CHIP CAP C 220P 50V K0402 X7R | R2_SA;HF_SA;G_SA; | Released | MURATA;AVX;TAIYO;PHYCOMN;DARFON | GRM155R71H221KA01D;04025C221KAT2A;UMK105BJ221KV-F;223858715614;C1005X7R221KGT | Multiple |  | Purchase | SMT | 1 | PCS | PC10 |
| 2 | 55.B0701.S20G | 78.22321.2FL | CHIP CAP 0.022U 16V K0402 X7R | R2_SA;HF_SA;G_SA; | Released | AVX;MURATA;PHYCOMP;TAIYO;TDK;DARFON;WALSIN | 0402YC223KAT2A;GRM155R71C223KA01D;223878715641;EMK105BJ223KV-F(EMK105B7223KV-F);C1005X7R1C223KT;C1005X7R223KET;0402B223K160CT | Multiple |  | Purchase | SMT | 2 | PCS | PC16 PC17 |
| 2 | 55.B0701.S20G | 78.22421.2BL | CHIP CAP C 0.22U 16V K0603 X7R | R2_SA;HF_SA;G_SA; | Released | MURATA;TAIYO;TDK;PHYCOMP;DARFON | GRM188R71C224KA01D;EMK107B7224KA-T;C1608X7R1C224KT;223878615654;C1608X7R224KET | Multiple |  | Purchase | SMT | 4 | PCS | PC109 PC13 PC46 PC56 |
| 2 | 55.B0701.S20G | 78.22421.2FL | CHIP CAP C 0.22U 16V K0402 X7R | R2_SA;HF_SA;G_SA; | Released | MURATA;TDK;SAMSUNG;DARFON;TAIYO | GRM155R71C224KA12D;C1005X7R1C224KT;CL05B224KO5NNNC;C1005X7R224KET;EMK105B7224KV-FR | Multiple |  | Purchase | SMT | 1 | PCS | C75 |
| 2 | 55.B0701.S20G | 78.22423.5FL | CHIP CAP C 0.22U 10V K0402 X5R | R2_SA;HF_SA;G_SA; | Released | MURATA;TDK;TAIYO;PHYCOMN;DARFON;WALSIN | GRM155R61A224KE19D;C1005X5R1A224KT000E;LMK105BJ224KV-F;223824713654;C1005X5R224KDT;0402X224K100CT | Multiple |  | Purchase | SMT | 4 | PCS | PC24 PC48 PC55 PC70 |
| 2 | 55.B0701.S20G | 78.22523.5FL | CHIP CAP C 2.2U 10V K0402 X5R | R2_SA;HF_SA;G_SA; | Released | DARFON;TAIYO;PHYCOMP;WALSIN;MURATA | C1005X5R225KDT;LMK105BJ225MV-F;225524713667;0402X225K100CT;GRM155R61A225KE95D | Multiple |  | Purchase | SMT | 8 | PCS | C185 C191 C199 C205 C210 C214 C251 C5 |
| 2 | 55.B0701.S20G | 78.22610.51L | CHIP CAP C 22U 6.3V M0805 X5R | R2_SA;HF_SA;G_SA; | Released | MURATA;TAIYO;TDK;KEMET;PANASONIC;MATSUKI;SAMSUNG;DARFON;WALSIN;YAGEO;AVX | GRM21BR60J226ME39L;JMK212BJ226MG-T;C2012X5R0J226MT;C0805C226M9PAC;ECJ2FB0J226M;MAG05X5R0J226M;CL21A226MQQNNNE;C2012X5R226MCP;0805X226M6R3CT;CC0805MKX5R5BB226;CV21X5R226M06AT | Multiple |  | Purchase | SMT | 24 | PCS | C126 C161 C168 C179 C188 C260 C9 PC100 PC112 PC113 PC120 PC123 PC124 PC155 PC160 PC161 PC162 PC163 PC166 PC170 PC171 PC177 PC83 PC96 |
| 2 | 55.B0701.S20G | 78.22610.5BL | CHIP CAP C 22U 6.3V M0603 X5R | R2_SA;HF_SA;G_SA; | Released | MURATA;TDK;SAMSUNG;TAIYO;DARFON | GRM188R60J226MEA0D;C1608X5R0J226MT;CL10A226MQ8NRNC;JDK107BBJ226MA-T;C1608X5R226MCT | Multiple |  | Purchase | SMT | 6 | PCS | PC149 PC36 PC42 PC44 PC47 PC51 |
| 2 | 55.B0701.S20G | 78.22612.51L | CHIP CAP C 22U 25V M0805 X5R | R2_SA;HF_SA;G_SA; | Released | MURATA;SANSUNG;DARFON;TDK | GRM21BR61E226ME44L;CL21A226MAQNNNE;C2012X5R226MFP;C2012X5R1E226MT | Multiple |  | Purchase | SMT | 15 | PCS | C318 C319 C320 C321 PC102 PC182 PC184 PC186 PC187 PC81 PC84 PC85 PC91 PC92 PC94 |
| 2 | 55.B0701.S20G | 78.22623.52L | CHIP CAP C 22U 10V K1206 X5R | R2_SA;HF_SA;G_SA; | Released | MURATA ; SAMSUNG;HOLYSTONE;TDK | GRM31CR61A226KE19L ; CL31A226KPHNNNE;C1206B226K010T;C3216X5R1A226KT | Multiple |  | Purchase | SMT | 1 | PCS | PC19 |
| 2 | 55.B0701.S20G | 78.27044.1FL | CHIP CAP C 27P 50V G0402 NPO | R2_SA;HF_SA;G_SA; | Released | DARFON ; PHYCOMP ; YAGEO ; WALSIN | C1005NP0270GGT ; 223886914279 ; CC0402GRNPO9BN270 ; 0402N270G500CT | Multiple |  | Purchase | SMT | 2 | PCS | C65 C66 |
| 2 | 55.B0701.S20G | 78.33124.2FL | CHIP CAP C 330P 50V K0402 X7R | R2_SA;HF_SA;G_SA; | Released | MURATA;AVX;TDK;TAIYO;PHYCOMN | GRM155R71H331KA01D;04025C331KAT2A;C1005X7R1H331KT000F;UMK105BJ331KV-F;223858715616 | Multiple |  | Purchase | SMT | 1 | PCS | PC191 |
| 2 | 55.B0701.S20G | 78.33224.2BL | CHIP CAP C 3300P 50V K0603 X7R | R2_SA;HF_SA;G_SA; | Released | PHYCOMP;MURATA;AVX;SAMSUNG;DARFON | 223858615629;GRM188R71H332KA01D-50v;06035C332KAT2A;CL10B332KB8NNNC;C1608X7R332KGT | Multiple |  | Purchase | SMT | 1 | PCS | PC69 |
| 2 | 55.B0701.S20G | 78.33420.5FL | CHIP CAP C 0.33U 6.3V K0402 X5 | R2_SA;HF_SA;G_SA; | Released | MURATA;TDK | GRM155R60J334KE01D;C1005X5R0J334KT000F | Multiple |  | Purchase | SMT | 2 | PCS | PC189 PC68 |
| 2 | 55.B0701.S20G | 78.47124.2FL | CHIP CAP C 470P50V K0402 X7R | R2_SA;HF_SA;G_SA; | Released | AVX;DARFON;MURATA;PHYCOMP;TAIYO;TDK;SAMSUNG;WALSIN;YAGEO | 04025C471KAT2A;C1005X7R471KGT;GRM155R71H471KA01D;223858715618;UMK105BJ471KV-F;C1005X7R1H471KT000F;CL05B471KB5NNNC;0402B471K500CT;CC0402KRX7R9BB471 | Multiple |  | Purchase | SMT | 4 | PCS | PC132 PC194 PC2 PC76 |
| 2 | 55.B0701.S20G | 78.47224.2FL | CHIP CAP C 4700P 50V K0402 X7 | R2_SA;HF_SA;G_SA; | Released | MURATA;AVX;TDK;TAYIO;PHYCOMN;DARFON | GRM155R71H472KA01D;04025C472KAT2A;C1005X7R1H472KT000F;UMK105BJ472KV-F;223858715632;C1005X7R472KGT | Multiple |  | Purchase | SMT | 2 | PCS | PC148 PC67 |
| 2 | 55.B0701.S20G | 78.47322.2FL | CHIP CAP C 0.047U 25V K0402 X7 | R2_SA;HF_SA;G_SA; | Released | MURATA;TDK;DARFON;PHYCOMP;WALSIN | GRM155R71E473KA88D;C1005X7R1E473KT000F;C1005X7R473KFT;223891715645;0402B473K250CT | Multiple |  | Purchase | SMT | 4 | PCS | C312 C313 C315 C316 |
| 2 | 55.B0701.S20G | 78.47523.5BL | CHIP CAP C 4.7U 10V K0603 X5R | R2_SA;HF_SA;G_SA; | Released | MURATA;TAIYO;MATSUKI;DARFON;SAMSUNG;PHYCOMP;TDK;WALSIN;AVX | GRM188R61A475KE15D;LMK107BJ475KA-T;MAG03X5R1A475K;C1608X5R475KDT;CL10A475KP8NNNC;223824613672C1608X5R1A475KT000N;0603X475K100CT;CV105X5R475K10AT | Multiple |  | Purchase | SMT | 3 | PCS | PC212 PC40 PC41 |
| 2 | 55.B0701.S20G | 78.47610.51L | CHIP CAP C 47U 6.3V M0805 X5R | R2_SA;HF_SA;G_SA; | Released | TAIYO;SAMSUNG;MURATA;TDK | JMK212BJ476MG-T;CL21A476MQYNNNE;GRM21BR60J476ME15;C2012X5R0J476MT00HE | Multiple |  | Purchase | SMT | 31 | PCS | C359 C360 C361 C362 C363 C364 C365 C366 C367 C368 C369 C370 C371 C372 C373 C374 PC135 PC136 PC144 PC145 PC27 PC28 PC29 PC30 PC31 PC37 PC38 PC39 PC59 PC60 PC7 |
| 2 | 55.B0701.S20G | 78.47611.53L | CHIP CAP C 47U 16V M1210 X5R | R2_SA;HF_SA;G_SA; | Released | MURATA;TAIYO;TAIYO | GRM32ER61C476ME15L;EMK325BJ476MM-T;EMK325BJ476MM-P | Multiple |  | Purchase | SMT | 3 | PCS | PC12 PC183 PC6 |
| 2 | 55.B0701.S20G | 78.5R074.1FL | CHIP CAP C 5P 50V C0402 NPO | R2_SA;HF_SA;G_SA; | Released | AVX;MURATA;PHYCOMP;TAIYO;DARFON;MURATA;WALSIN;SAMSUNG;YAGEO | CM05CG5R0C50AH;GRM1555C1H5R0CZ01D;223886914508;UMK105CG050CW-F;C1005NP0509CGT;GRM1555C1H5R0CA01D;0402N5R0C500LT;CL05C050CB5NNNC;CC0402CRNPO9BN5R0 | Multiple |  | Purchase | SMT | 2 | PCS | PC104 PC126 |
| 2 | 55.B0701.S20G | 78.68034.1FL | CHIP CAP 68P 50V J 0402 NPO | R2_SA;HF_SA;G_SA; | Released | MURATA;TDK;PHYCOMP;TAIYO;;DARFON;SAMSUNG;AVX;MURATA;WALSIN | GRM1555C1H680JZ01D;C1005C0G1H680JT;223886915689;UMK105CH680JW-F;C1005NP0680JGT;CL05C680JB5NNNC;CM05CG680J50AH;GRM1555C1H680JA01D;0402N680J500CT | Multiple |  | Purchase | SMT | 1 | PCS | PC105 |
| 2 | 55.B0701.S20G | 78.68124.2FL | CHIP CAP C 680P 50V K0402 X7R | R2_SA;HF_SA;G_SA; | Released | AVX;DARFON;MURATA;PHYCOMP;TAIYO;TDK;WALSIN | CM05X7R681K50AT;C1005X7R681KGT;GRM155R71H681KA01D;223858715621;UMK105BJ681KV-F;C1005X7R1H681KT;0402B681K500CT | Multiple |  | Purchase | SMT | 2 | PCS | PC101 PC121 |
| 2 | 55.B0701.S20G | 78.68321.2FL | CHIP CAP C 0.068U 16V K0402 X7 | R2_SA;HF_SA;G_SA; | Released | MURATA;TDK;PHYCOMN;DARFON;SAMSUNG | GRM155R71C683KA88D;C1005X7R1C683KT000F;223878715647;C1005X7R683KET;CL05B683K05NNNC | Multiple |  | Purchase | SMT | 1 | PCS | PC15 |
| 2 | 55.B0701.S20G | 78.6R074.1FL | CHIP CAP C 6P 50V C0402 NPO | R2_SA;HF_SA;G_SA; | Released | DARFON;MURATA;PHYCOMP;MURATA | C1005NP0609CGT;GRM1555C1H6R0CZ01D;223886914608;GRM1555C1H6R0CA01D | Multiple |  | Purchase | SMT | 2 | PCS | C26 C33 |
| 2 | 55.B0701.S20G | 79.47719.2BL | CHIP CAP 470UF 2V EEFSX0D471X | R2_SA;HF_SA;G_SA; | Released | PANASONIC | EEFSX0D471XE | Single |  | Purchase | SMT | 5 | PCS | PTC1 PTC2 PTC3 PTC4 PTC5 |
| 2 | 55.B0701.S20G | 82.30001.931 | XTAL 32.768KHZ 8P20PPM DST310S | R2_SA; | Released | KDS | 1TJF080DP1A000A | Single |  | Purchase | SMT | 1 | PCS | X1 |
| 2 | 55.B0701.S20G | 82.30005.A81 | XTAL 14.31818M 20P30PPM 5*3.2 | R2_SA; | Released | TXC | 7A14300038 | Single |  | Purchase | SMT | 1 | PCS | X2 |
| 2 | 55.B0701.S20G | 83.00190.V70 | LED 1.6*0.8 BLUE LTST-C190TBKT | R2_SA;G_SA; | Released | LITEON | LTST-C190TBKT | Single |  | Purchase | SMT | 1 | PCS | LED1 |
| 2 | 55.B0701.S20G | 83.01921.C70 | LED 1.6*0.8 YEL 19-21UYOC/S530 | R2_SA;HF_SA;G_SA; | Released | EVERLIGHT | 19-21UYOC/S530-A2TR8 | Single |  | Purchase | SMT | 1 | PCS | LED14 |
| 2 | 55.B0701.S20G | 83.01921.S70 | LED Y/G 19-21/G6C-BM2P1B/3T SM | R2_SA;HF_SA;G_SA; | Released | EVERLIGHT | 19-21/G6C-BM2P1B/3T | Single |  | Purchase | SMT | 14 | PCS | LED10 LED11 LED12 LED15 LED16 LED17 LED2 LED3 LED4 LED5 LED6 LED7 LED8 LED9 |
| 2 | 55.B0701.S20G | 83.5R603.E3F | DIODE ZEN 5.6V MM3Z5V6T1G SOD | R2_SA;HF_SA; | Released | ON | MM3Z5V6T1G | Single |  | Purchase | SMT | 2 | PCS | PD1 PD2 |
| 2 | 55.B0701.S20G | 84.00359.C31 | FET MOS FDN359BN NC SUPERSOT23 | R2_SA; | Released | FAIRCHILD | FDN359BN | Single |  | Purchase | SMT | 2 | PCS | Q3 Q8 |
| 2 | 55.B0701.S20G | 84.04406.B37 | FET MOS AO4406AL NC SO-8(HF) | R2_SA;HF_SA;G_SA; | Released | AOS | AO4406AL | Single |  | Purchase | SMT | 1 | PCS | Q4 |
| 2 | 55.B0701.S20G | 84.08200.037 | FET MOS FDMC8200 NC POWER33 | R2_SA;HF_SA;G_SA; | Released | FAIRCHILD | FDMC8200 | Single |  | Purchase | SMT | 1 | PCS | PQ1 |
| 2 | 55.B0701.S20G | 84.27002.C3F | FET MOS 2N7002DW-7-F NC SOT363 | R2_SA;HF_SA; | Released | DIODES | 2N7002DW-7-F | Single |  | Purchase | SMT | 9 | PCS | U11 U24 U25 U29 U3 U30 U34 U8 U9 |
| 2 | 55.B0701.S20G | 84.2N702.E31 | FET MOS 2N7002A-7 NC SOT-23 ESD 1.2KV | R2_SA;HF_SA;G_SA; | Released | DIODES | 2N7002A-7 | Single |  | Purchase | SMT | 10 | PCS | Q10 Q13 Q14 Q15 Q16 Q17 Q18 Q5 Q6 Q9 |
| 2 | 55.B0701.S20G | 84.M3904.01K | XTOR MMBT3904TT1G NPN SOT-416 | R2_SA; | Released | ON | MMBT3904TT1G | Single |  | Purchase | SMT | 7 | PCS | PQ2 PQ3 Q1 Q11 Q12 Q2 Q7 |
| 1 | 55.B0701.D20G | 72.25Q64.F01 | IC FALSH MEM W25Q64FVSSIG 8P 8M-BYTE | R2_SA;HF_SA; | Released | WINBOND | W25Q64FVSSIG | Single |  | Purchase | DIP | 1 | PCS | U18 |
